(kicad_pcb
	(version 20260206)
	(generator "pcbnew")
	(generator_version "10.0")
	(general
		(thickness 1.6)
		(legacy_teardrops no)
	)
	(paper "A4")
	(title_block
		(title "9054_F0T_PDB_BD_GPU_F_V04_1213_1550_OCP.brd")
		(comment 1 "Grand Teton / footprints 469-475 of 608")
	)
	(layers
		(0 "F.Cu" signal "TOP")
		(4 "In1.Cu" signal "GND")
		(6 "In2.Cu" signal "IN1")
		(8 "In3.Cu" signal "GND1")
		(10 "In4.Cu" signal "VCC")
		(12 "In5.Cu" signal "VCC1")
		(14 "In6.Cu" signal "GND2")
		(16 "In7.Cu" signal "IN2")
		(18 "In8.Cu" signal "GND3")
		(2 "B.Cu" signal "BOTTOM")
		(9 "F.Adhes" user "F.Adhesive")
		(11 "B.Adhes" user "B.Adhesive")
		(13 "F.Paste" user "Package Geometry/Pastemask Top")
		(15 "B.Paste" user "Package Geometry/Pastemask Bottom")
		(5 "F.SilkS" user "Ref Des/Silkscreen Top")
		(7 "B.SilkS" user "Ref Des/Silkscreen Bottom")
		(1 "F.Mask" user "Board Geometry/Soldermask Top")
		(3 "B.Mask" user "Board Geometry/Soldermask Bottom")
		(17 "Dwgs.User" user "User.Drawings")
		(19 "Cmts.User" user "User.Comments")
		(21 "Eco1.User" user "User.Eco1")
		(23 "Eco2.User" user "User.Eco2")
		(25 "Edge.Cuts" user "Board Geometry/Outline")
		(27 "Margin" user)
		(31 "F.CrtYd" user "Package Geometry/Place Bound Top")
		(29 "B.CrtYd" user "Package Geometry/Place Bound Bottom")
		(35 "F.Fab" user "Ref Des/Assembly Top")
		(33 "B.Fab" user "Ref Des/Assembly Bottom")
	)
	(footprint ""
		(layer "B.Cu")
		(at 293.5224 -63.373)
		(property "Reference" "PC5"
			(at 0 0 0)
			(layer "B.SilkS")
			(hide yes)
			(effects
				(font
					(size 1.27 1.27)
				)
				(justify mirror)
			)
		)
		(property "Value" ""
			(at 0 0 0)
			(layer "B.Fab")
			(effects
				(font
					(size 1.27 1.27)
				)
				(justify mirror)
			)
		)
		(duplicate_pad_numbers_are_jumpers no)
		(fp_line
			(start -0.7874 -0.4064)
			(end -0.7874 0.4064)
			(stroke
				(width 0.1524)
				(type default)
			)
			(layer "B.SilkS")
		)
		(fp_line
			(start -0.7874 0.4064)
			(end 0.7874 0.4064)
			(stroke
				(width 0.1524)
				(type default)
			)
			(layer "B.SilkS")
		)
		(fp_line
			(start 0.7874 -0.4064)
			(end -0.7874 -0.4064)
			(stroke
				(width 0.1524)
				(type default)
			)
			(layer "B.SilkS")
		)
		(fp_line
			(start 0.7874 0.4064)
			(end 0.7874 -0.4064)
			(stroke
				(width 0.1524)
				(type default)
			)
			(layer "B.SilkS")
		)
		(fp_line
			(start -0.67945 -0.3048)
			(end -0.67945 0.3048)
			(stroke
				(width 0.1)
				(type default)
			)
			(layer "B.Fab")
		)
		(fp_line
			(start -0.67945 0.3048)
			(end -0.120396 0.3048)
			(stroke
				(width 0.1)
				(type default)
			)
			(layer "B.Fab")
		)
		(fp_line
			(start -0.12065 -0.3048)
			(end -0.67945 -0.3048)
			(stroke
				(width 0.1)
				(type default)
			)
			(layer "B.Fab")
		)
		(fp_line
			(start -0.12065 -0.2794)
			(end -0.12065 -0.3048)
			(stroke
				(width 0.1)
				(type default)
			)
			(layer "B.Fab")
		)
		(fp_line
			(start -0.120396 0.2794)
			(end 0.12065 0.2794)
			(stroke
				(width 0.1)
				(type default)
			)
			(layer "B.Fab")
		)
		(fp_line
			(start -0.120396 0.3048)
			(end -0.120396 0.2794)
			(stroke
				(width 0.1)
				(type default)
			)
			(layer "B.Fab")
		)
		(fp_line
			(start 0.12065 -0.305054)
			(end 0.12065 -0.2794)
			(stroke
				(width 0.1)
				(type default)
			)
			(layer "B.Fab")
		)
		(fp_line
			(start 0.12065 -0.2794)
			(end -0.12065 -0.2794)
			(stroke
				(width 0.1)
				(type default)
			)
			(layer "B.Fab")
		)
		(fp_line
			(start 0.12065 0.2794)
			(end 0.12065 0.3048)
			(stroke
				(width 0.1)
				(type default)
			)
			(layer "B.Fab")
		)
		(fp_line
			(start 0.12065 0.3048)
			(end 0.67945 0.3048)
			(stroke
				(width 0.1)
				(type default)
			)
			(layer "B.Fab")
		)
		(fp_line
			(start 0.67945 -0.305054)
			(end 0.12065 -0.305054)
			(stroke
				(width 0.1)
				(type default)
			)
			(layer "B.Fab")
		)
		(fp_line
			(start 0.67945 0.3048)
			(end 0.67945 -0.305054)
			(stroke
				(width 0.1)
				(type default)
			)
			(layer "B.Fab")
		)
		(pad "1" smd circle
			(at 0.40005 0 180)
			(size 0 0)
			(layers "B.Cu" "B.Mask" "B.Paste")
			(net "GND_FIELD_SIGNAL")
		)
		(pad "2" smd circle
			(at -0.40005 0 180)
			(size 0 0)
			(layers "B.Cu" "B.Mask" "B.Paste")
			(net "P52V_HS1_DVCC")
		)
	)
	(footprint ""
		(layer "B.Cu")
		(at 272.4404 -84.201 90)
		(property "Reference" "PR4"
			(at 0 0 90)
			(layer "B.SilkS")
			(hide yes)
			(effects
				(font
					(size 1.27 1.27)
				)
				(justify mirror)
			)
		)
		(property "Value" ""
			(at 0 0 90)
			(layer "B.Fab")
			(effects
				(font
					(size 1.27 1.27)
				)
				(justify mirror)
			)
		)
		(duplicate_pad_numbers_are_jumpers no)
		(fp_line
			(start 1.651 -0.8382)
			(end -1.651 -0.8382)
			(stroke
				(width 0.1524)
				(type default)
			)
			(layer "B.SilkS")
		)
		(fp_line
			(start -1.651 -0.8382)
			(end -1.651 0.8382)
			(stroke
				(width 0.1524)
				(type default)
			)
			(layer "B.SilkS")
		)
		(fp_line
			(start 1.651 0.8382)
			(end 1.651 -0.8382)
			(stroke
				(width 0.1524)
				(type default)
			)
			(layer "B.SilkS")
		)
		(fp_line
			(start -1.651 0.8382)
			(end 1.651 0.8382)
			(stroke
				(width 0.1524)
				(type default)
			)
			(layer "B.SilkS")
		)
		(fp_line
			(start 1.559814 -0.7366)
			(end 1.559814 0.7366)
			(stroke
				(width 0.1)
				(type default)
			)
			(layer "B.Fab")
		)
		(fp_line
			(start 1.524 -0.7366)
			(end 1.559814 -0.7366)
			(stroke
				(width 0.1)
				(type default)
			)
			(layer "B.Fab")
		)
		(fp_line
			(start -1.524 -0.7366)
			(end 1.524 -0.7366)
			(stroke
				(width 0.1)
				(type default)
			)
			(layer "B.Fab")
		)
		(fp_line
			(start -1.560576 -0.7366)
			(end -1.524 -0.7366)
			(stroke
				(width 0.1)
				(type default)
			)
			(layer "B.Fab")
		)
		(fp_line
			(start 1.559814 0.7366)
			(end 1.524 0.7366)
			(stroke
				(width 0.1)
				(type default)
			)
			(layer "B.Fab")
		)
		(fp_line
			(start 1.524 0.7366)
			(end -1.524 0.7366)
			(stroke
				(width 0.1)
				(type default)
			)
			(layer "B.Fab")
		)
		(fp_line
			(start -1.524 0.7366)
			(end -1.560576 0.7366)
			(stroke
				(width 0.1)
				(type default)
			)
			(layer "B.Fab")
		)
		(fp_line
			(start -1.560576 0.7366)
			(end -1.560576 -0.7366)
			(stroke
				(width 0.1)
				(type default)
			)
			(layer "B.Fab")
		)
		(pad "1" smd rect
			(at 0.94996 0 90)
			(size 1.1176 1.3716)
			(layers "B.Cu" "B.Mask" "B.Paste")
			(net "P52V_1")
		)
		(pad "2" smd rect
			(at -0.94996 0 90)
			(size 1.1176 1.3716)
			(layers "B.Cu" "B.Mask" "B.Paste")
			(net "P52V_HS1_UVH")
		)
	)
	(footprint ""
		(layer "B.Cu")
		(at 149.86 -52.959)
		(property "Reference" ""
			(at 0 0 0)
			(layer "B.SilkS")
			(hide yes)
			(effects
				(font
					(size 1.27 1.27)
				)
				(justify mirror)
			)
		)
		(property "Value" ""
			(at 0 0 0)
			(layer "B.Fab")
			(effects
				(font
					(size 1.27 1.27)
				)
				(justify mirror)
			)
		)
		(duplicate_pad_numbers_are_jumpers no)
		(pad "1" smd circle
			(at 0 0 180)
			(size 0.9906 0.9906)
			(layers "B.Cu" "B.Mask" "B.Paste")
			(net "Net_240")
		)
		(zone
			(layer "B.Cu")
			(hatch none 0.5)
			(connect_pads
				(clearance 0)
			)
			(min_thickness 0.25)
			(keepout
				(tracks not_allowed)
				(vias allowed)
				(pads allowed)
				(copperpour not_allowed)
				(footprints allowed)
			)
			(placement
				(enabled no)
				(sheetname "")
			)
			(fill
				(thermal_gap 0.5)
				(thermal_bridge_width 0.5)
				(island_removal_mode 0)
			)
			(polygon
				(pts
					(arc
						(start 151.4856 -52.959)
						(mid 148.2344 -52.959)
						(end 151.4856 -52.959)
					)
				)
			)
		)
	)
	(footprint ""
		(layer "B.Cu")
		(at 422.3004 -35.052 180)
		(property "Reference" "C102"
			(at 0 0 0)
			(layer "B.SilkS")
			(hide yes)
			(effects
				(font
					(size 1.27 1.27)
				)
				(justify mirror)
			)
		)
		(property "Value" ""
			(at 0 0 0)
			(layer "B.Fab")
			(effects
				(font
					(size 1.27 1.27)
				)
				(justify mirror)
			)
		)
		(duplicate_pad_numbers_are_jumpers no)
		(fp_line
			(start 0.7874 0.4064)
			(end 0.7874 -0.4064)
			(stroke
				(width 0.1524)
				(type default)
			)
			(layer "B.SilkS")
		)
		(fp_line
			(start 0.7874 -0.4064)
			(end -0.7874 -0.4064)
			(stroke
				(width 0.1524)
				(type default)
			)
			(layer "B.SilkS")
		)
		(fp_line
			(start -0.7874 0.4064)
			(end 0.7874 0.4064)
			(stroke
				(width 0.1524)
				(type default)
			)
			(layer "B.SilkS")
		)
		(fp_line
			(start -0.7874 -0.4064)
			(end -0.7874 0.4064)
			(stroke
				(width 0.1524)
				(type default)
			)
			(layer "B.SilkS")
		)
		(fp_line
			(start 0.67945 0.3048)
			(end 0.67945 -0.305054)
			(stroke
				(width 0.1)
				(type default)
			)
			(layer "B.Fab")
		)
		(fp_line
			(start 0.67945 -0.305054)
			(end 0.12065 -0.305054)
			(stroke
				(width 0.1)
				(type default)
			)
			(layer "B.Fab")
		)
		(fp_line
			(start 0.12065 0.3048)
			(end 0.67945 0.3048)
			(stroke
				(width 0.1)
				(type default)
			)
			(layer "B.Fab")
		)
		(fp_line
			(start 0.12065 0.2794)
			(end 0.12065 0.3048)
			(stroke
				(width 0.1)
				(type default)
			)
			(layer "B.Fab")
		)
		(fp_line
			(start 0.12065 -0.2794)
			(end -0.12065 -0.2794)
			(stroke
				(width 0.1)
				(type default)
			)
			(layer "B.Fab")
		)
		(fp_line
			(start 0.12065 -0.305054)
			(end 0.12065 -0.2794)
			(stroke
				(width 0.1)
				(type default)
			)
			(layer "B.Fab")
		)
		(fp_line
			(start -0.120396 0.3048)
			(end -0.120396 0.2794)
			(stroke
				(width 0.1)
				(type default)
			)
			(layer "B.Fab")
		)
		(fp_line
			(start -0.120396 0.2794)
			(end 0.12065 0.2794)
			(stroke
				(width 0.1)
				(type default)
			)
			(layer "B.Fab")
		)
		(fp_line
			(start -0.12065 -0.2794)
			(end -0.12065 -0.3048)
			(stroke
				(width 0.1)
				(type default)
			)
			(layer "B.Fab")
		)
		(fp_line
			(start -0.12065 -0.3048)
			(end -0.67945 -0.3048)
			(stroke
				(width 0.1)
				(type default)
			)
			(layer "B.Fab")
		)
		(fp_line
			(start -0.67945 0.3048)
			(end -0.120396 0.3048)
			(stroke
				(width 0.1)
				(type default)
			)
			(layer "B.Fab")
		)
		(fp_line
			(start -0.67945 -0.3048)
			(end -0.67945 0.3048)
			(stroke
				(width 0.1)
				(type default)
			)
			(layer "B.Fab")
		)
		(pad "1" smd circle
			(at 0.40005 0)
			(size 0 0)
			(layers "B.Cu" "B.Mask" "B.Paste")
			(net "P3V3_AUX")
		)
		(pad "2" smd circle
			(at -0.40005 0)
			(size 0 0)
			(layers "B.Cu" "B.Mask" "B.Paste")
			(net "GND")
		)
	)
	(footprint ""
		(layer "B.Cu")
		(at 110.2614 -55.626 90)
		(property "Reference" "R5865"
			(at 0 0 90)
			(layer "B.SilkS")
			(hide yes)
			(effects
				(font
					(size 1.27 1.27)
				)
				(justify mirror)
			)
		)
		(property "Value" ""
			(at 0 0 90)
			(layer "B.Fab")
			(effects
				(font
					(size 1.27 1.27)
				)
				(justify mirror)
			)
		)
		(duplicate_pad_numbers_are_jumpers no)
		(fp_line
			(start 0.7874 -0.4064)
			(end -0.7874 -0.4064)
			(stroke
				(width 0.1524)
				(type default)
			)
			(layer "B.SilkS")
		)
		(fp_line
			(start -0.7874 -0.4064)
			(end -0.7874 0.4064)
			(stroke
				(width 0.1524)
				(type default)
			)
			(layer "B.SilkS")
		)
		(fp_line
			(start 0.7874 0.4064)
			(end 0.7874 -0.4064)
			(stroke
				(width 0.1524)
				(type default)
			)
			(layer "B.SilkS")
		)
		(fp_line
			(start -0.7874 0.4064)
			(end 0.7874 0.4064)
			(stroke
				(width 0.1524)
				(type default)
			)
			(layer "B.SilkS")
		)
		(fp_line
			(start 0.67945 -0.305054)
			(end 0.12065 -0.305054)
			(stroke
				(width 0.1)
				(type default)
			)
			(layer "B.Fab")
		)
		(fp_line
			(start 0.12065 -0.305054)
			(end 0.12065 -0.2794)
			(stroke
				(width 0.1)
				(type default)
			)
			(layer "B.Fab")
		)
		(fp_line
			(start -0.12065 -0.3048)
			(end -0.67945 -0.3048)
			(stroke
				(width 0.1)
				(type default)
			)
			(layer "B.Fab")
		)
		(fp_line
			(start -0.67945 -0.3048)
			(end -0.67945 0.3048)
			(stroke
				(width 0.1)
				(type default)
			)
			(layer "B.Fab")
		)
		(fp_line
			(start 0.12065 -0.2794)
			(end -0.12065 -0.2794)
			(stroke
				(width 0.1)
				(type default)
			)
			(layer "B.Fab")
		)
		(fp_line
			(start -0.12065 -0.2794)
			(end -0.12065 -0.3048)
			(stroke
				(width 0.1)
				(type default)
			)
			(layer "B.Fab")
		)
		(fp_line
			(start 0.12065 0.2794)
			(end 0.12065 0.3048)
			(stroke
				(width 0.1)
				(type default)
			)
			(layer "B.Fab")
		)
		(fp_line
			(start -0.120396 0.2794)
			(end 0.12065 0.2794)
			(stroke
				(width 0.1)
				(type default)
			)
			(layer "B.Fab")
		)
		(fp_line
			(start 0.67945 0.3048)
			(end 0.67945 -0.305054)
			(stroke
				(width 0.1)
				(type default)
			)
			(layer "B.Fab")
		)
		(fp_line
			(start 0.12065 0.3048)
			(end 0.67945 0.3048)
			(stroke
				(width 0.1)
				(type default)
			)
			(layer "B.Fab")
		)
		(fp_line
			(start -0.120396 0.3048)
			(end -0.120396 0.2794)
			(stroke
				(width 0.1)
				(type default)
			)
			(layer "B.Fab")
		)
		(fp_line
			(start -0.67945 0.3048)
			(end -0.120396 0.3048)
			(stroke
				(width 0.1)
				(type default)
			)
			(layer "B.Fab")
		)
		(pad "1" smd circle
			(at 0.40005 0 270)
			(size 0 0)
			(layers "B.Cu" "B.Mask" "B.Paste")
			(net "P52V_HS2_GATE1_R")
		)
		(pad "2" smd circle
			(at -0.40005 0 270)
			(size 0 0)
			(layers "B.Cu" "B.Mask" "B.Paste")
			(net "P52V_HS2_4287_GATE_R")
		)
	)
	(footprint ""
		(layer "B.Cu")
		(at 295.656 -85.852)
		(property "Reference" "C104"
			(at 0 0 0)
			(layer "B.SilkS")
			(hide yes)
			(effects
				(font
					(size 1.27 1.27)
				)
				(justify mirror)
			)
		)
		(property "Value" ""
			(at 0 0 0)
			(layer "B.Fab")
			(effects
				(font
					(size 1.27 1.27)
				)
				(justify mirror)
			)
		)
		(duplicate_pad_numbers_are_jumpers no)
		(fp_line
			(start -0.7874 -0.4064)
			(end -0.7874 0.4064)
			(stroke
				(width 0.1524)
				(type default)
			)
			(layer "B.SilkS")
		)
		(fp_line
			(start -0.7874 0.4064)
			(end 0.7874 0.4064)
			(stroke
				(width 0.1524)
				(type default)
			)
			(layer "B.SilkS")
		)
		(fp_line
			(start 0.7874 -0.4064)
			(end -0.7874 -0.4064)
			(stroke
				(width 0.1524)
				(type default)
			)
			(layer "B.SilkS")
		)
		(fp_line
			(start 0.7874 0.4064)
			(end 0.7874 -0.4064)
			(stroke
				(width 0.1524)
				(type default)
			)
			(layer "B.SilkS")
		)
		(fp_line
			(start -0.67945 -0.3048)
			(end -0.67945 0.3048)
			(stroke
				(width 0.1)
				(type default)
			)
			(layer "B.Fab")
		)
		(fp_line
			(start -0.67945 0.3048)
			(end -0.120396 0.3048)
			(stroke
				(width 0.1)
				(type default)
			)
			(layer "B.Fab")
		)
		(fp_line
			(start -0.12065 -0.3048)
			(end -0.67945 -0.3048)
			(stroke
				(width 0.1)
				(type default)
			)
			(layer "B.Fab")
		)
		(fp_line
			(start -0.12065 -0.2794)
			(end -0.12065 -0.3048)
			(stroke
				(width 0.1)
				(type default)
			)
			(layer "B.Fab")
		)
		(fp_line
			(start -0.120396 0.2794)
			(end 0.12065 0.2794)
			(stroke
				(width 0.1)
				(type default)
			)
			(layer "B.Fab")
		)
		(fp_line
			(start -0.120396 0.3048)
			(end -0.120396 0.2794)
			(stroke
				(width 0.1)
				(type default)
			)
			(layer "B.Fab")
		)
		(fp_line
			(start 0.12065 -0.305054)
			(end 0.12065 -0.2794)
			(stroke
				(width 0.1)
				(type default)
			)
			(layer "B.Fab")
		)
		(fp_line
			(start 0.12065 -0.2794)
			(end -0.12065 -0.2794)
			(stroke
				(width 0.1)
				(type default)
			)
			(layer "B.Fab")
		)
		(fp_line
			(start 0.12065 0.2794)
			(end 0.12065 0.3048)
			(stroke
				(width 0.1)
				(type default)
			)
			(layer "B.Fab")
		)
		(fp_line
			(start 0.12065 0.3048)
			(end 0.67945 0.3048)
			(stroke
				(width 0.1)
				(type default)
			)
			(layer "B.Fab")
		)
		(fp_line
			(start 0.67945 -0.305054)
			(end 0.12065 -0.305054)
			(stroke
				(width 0.1)
				(type default)
			)
			(layer "B.Fab")
		)
		(fp_line
			(start 0.67945 0.3048)
			(end 0.67945 -0.305054)
			(stroke
				(width 0.1)
				(type default)
			)
			(layer "B.Fab")
		)
		(pad "1" smd circle
			(at 0.40005 0 180)
			(size 0 0)
			(layers "B.Cu" "B.Mask" "B.Paste")
			(net "GND")
		)
		(pad "2" smd circle
			(at -0.40005 0 180)
			(size 0 0)
			(layers "B.Cu" "B.Mask" "B.Paste")
			(net "P3V3_AUX")
		)
	)
	(footprint ""
		(layer "B.Cu")
		(at 105.918 -41.148 90)
		(property "Reference" "PC597"
			(at 0 0 90)
			(layer "B.SilkS")
			(hide yes)
			(effects
				(font
					(size 1.27 1.27)
				)
				(justify mirror)
			)
		)
		(property "Value" ""
			(at 0 0 90)
			(layer "B.Fab")
			(effects
				(font
					(size 1.27 1.27)
				)
				(justify mirror)
			)
		)
		(duplicate_pad_numbers_are_jumpers no)
		(fp_line
			(start 1.2954 -0.5842)
			(end -1.2954 -0.5842)
			(stroke
				(width 0.1524)
				(type default)
			)
			(layer "B.SilkS")
		)
		(fp_line
			(start -1.2954 -0.5842)
			(end -1.2954 0.5842)
			(stroke
				(width 0.1524)
				(type default)
			)
			(layer "B.SilkS")
		)
		(fp_line
			(start 1.2954 0.5842)
			(end 1.2954 -0.5842)
			(stroke
				(width 0.1524)
				(type default)
			)
			(layer "B.SilkS")
		)
		(fp_line
			(start -1.2954 0.5842)
			(end 1.2954 0.5842)
			(stroke
				(width 0.1524)
				(type default)
			)
			(layer "B.SilkS")
		)
		(fp_line
			(start 0.8636 -0.4572)
			(end -0.8636 -0.4572)
			(stroke
				(width 0.1)
				(type default)
			)
			(layer "B.Fab")
		)
		(fp_line
			(start -0.8636 -0.4572)
			(end -0.8636 -0.4064)
			(stroke
				(width 0.1)
				(type default)
			)
			(layer "B.Fab")
		)
		(fp_line
			(start 1.1938 -0.4064)
			(end 0.8636 -0.4064)
			(stroke
				(width 0.1)
				(type default)
			)
			(layer "B.Fab")
		)
		(fp_line
			(start 0.8636 -0.4064)
			(end 0.8636 -0.4572)
			(stroke
				(width 0.1)
				(type default)
			)
			(layer "B.Fab")
		)
		(fp_line
			(start -0.8636 -0.4064)
			(end -1.1938 -0.4064)
			(stroke
				(width 0.1)
				(type default)
			)
			(layer "B.Fab")
		)
		(fp_line
			(start -1.1938 -0.4064)
			(end -1.1938 0.4064)
			(stroke
				(width 0.1)
				(type default)
			)
			(layer "B.Fab")
		)
		(fp_line
			(start 1.1938 0.4064)
			(end 1.1938 -0.4064)
			(stroke
				(width 0.1)
				(type default)
			)
			(layer "B.Fab")
		)
		(fp_line
			(start 0.8636 0.4064)
			(end 1.1938 0.4064)
			(stroke
				(width 0.1)
				(type default)
			)
			(layer "B.Fab")
		)
		(fp_line
			(start -0.8636 0.4064)
			(end -0.8636 0.4572)
			(stroke
				(width 0.1)
				(type default)
			)
			(layer "B.Fab")
		)
		(fp_line
			(start -1.1938 0.4064)
			(end -0.8636 0.4064)
			(stroke
				(width 0.1)
				(type default)
			)
			(layer "B.Fab")
		)
		(fp_line
			(start 0.8636 0.4572)
			(end 0.8636 0.4064)
			(stroke
				(width 0.1)
				(type default)
			)
			(layer "B.Fab")
		)
		(fp_line
			(start -0.8636 0.4572)
			(end 0.8636 0.4572)
			(stroke
				(width 0.1)
				(type default)
			)
			(layer "B.Fab")
		)
		(pad "1" smd rect
			(at 0.7366 0)
			(size 0.7112 0.8128)
			(layers "B.Cu" "B.Mask" "B.Paste")
			(net "P52V_HS2_4287_GATE2_R")
		)
		(pad "2" smd rect
			(at -0.7366 0)
			(size 0.7112 0.8128)
			(layers "B.Cu" "B.Mask" "B.Paste")
			(net "P52V_HS2")
		)
	)
)
